(kicad_pcb
	(version 20260206)
	(generator "pcbnew")
	(generator_version "10.0")
	(general
		(thickness 1.6)
		(legacy_teardrops no)
	)
	(paper "A4")
	(title_block
		(title "04192023_DAF0TMB3IC0_F0TG_MB_C_brd_V02_OCP.brd")
		(comment 1 "Grand Teton / footprints 4156-4161 of 8354")
	)
	(layers
		(0 "F.Cu" signal "TOP")
		(4 "In1.Cu" signal "GND")
		(6 "In2.Cu" signal "IN1")
		(8 "In3.Cu" signal "GND1")
		(10 "In4.Cu" signal "IN2")
		(12 "In5.Cu" signal "GND2")
		(14 "In6.Cu" signal "IN3")
		(16 "In7.Cu" signal "GND3")
		(18 "In8.Cu" signal "VCC")
		(20 "In9.Cu" signal "VCC1")
		(22 "In10.Cu" signal "GND4")
		(24 "In11.Cu" signal "IN4")
		(26 "In12.Cu" signal "GND5")
		(28 "In13.Cu" signal "IN5")
		(30 "In14.Cu" signal "GND6")
		(32 "In15.Cu" signal "IN6")
		(34 "In16.Cu" signal "GND7")
		(2 "B.Cu" signal "BOTTOM")
		(9 "F.Adhes" user "F.Adhesive")
		(11 "B.Adhes" user "B.Adhesive")
		(13 "F.Paste" user "Package Geometry/Pastemask Top")
		(15 "B.Paste" user "Package Geometry/Pastemask Bottom")
		(5 "F.SilkS" user "Ref Des/Silkscreen Top")
		(7 "B.SilkS" user "Ref Des/Silkscreen Bottom")
		(1 "F.Mask" user "Board Geometry/Soldermask Top")
		(3 "B.Mask" user "Board Geometry/Soldermask Bottom")
		(17 "Dwgs.User" user "User.Drawings")
		(19 "Cmts.User" user "User.Comments")
		(21 "Eco1.User" user "User.Eco1")
		(23 "Eco2.User" user "User.Eco2")
		(25 "Edge.Cuts" user "Board Geometry/Outline")
		(27 "Margin" user)
		(31 "F.CrtYd" user "Package Geometry/Place Bound Top")
		(29 "B.CrtYd" user "Package Geometry/Place Bound Bottom")
		(35 "F.Fab" user "Ref Des/Assembly Top")
		(33 "B.Fab" user "Ref Des/Assembly Bottom")
	)
	(footprint ""
		(layer "F.Cu")
		(at 320.900044 -61.999876)
		(property "Reference" "J48"
			(at 5.08 1.965452 0)
			(unlocked yes)
			(layer "F.SilkS")
			(effects
				(font
					(size 0.7874 0.5842)
					(thickness 0.1524)
				)
			)
		)
		(property "Value" ""
			(at 0 0 0)
			(layer "F.Fab")
			(effects
				(font
					(size 1.27 1.27)
				)
			)
		)
		(duplicate_pad_numbers_are_jumpers no)
		(fp_line
			(start -1.700022 -2.739898)
			(end 1.700022 -2.739898)
			(stroke
				(width 0.1524)
				(type default)
			)
			(layer "F.SilkS")
		)
		(fp_line
			(start -1.700022 -2.4257)
			(end -1.700022 -2.739898)
			(stroke
				(width 0.1524)
				(type default)
			)
			(layer "F.SilkS")
		)
		(fp_line
			(start -1.700022 -1.1557)
			(end -1.700022 -1.3843)
			(stroke
				(width 0.1524)
				(type default)
			)
			(layer "F.SilkS")
		)
		(fp_line
			(start -1.700022 0.1143)
			(end -1.700022 -0.1143)
			(stroke
				(width 0.1524)
				(type default)
			)
			(layer "F.SilkS")
		)
		(fp_line
			(start -1.700022 1.3843)
			(end -1.700022 1.1557)
			(stroke
				(width 0.1524)
				(type default)
			)
			(layer "F.SilkS")
		)
		(fp_line
			(start -1.700022 2.739898)
			(end -1.700022 2.4257)
			(stroke
				(width 0.1524)
				(type default)
			)
			(layer "F.SilkS")
		)
		(fp_line
			(start 1.700022 -2.739898)
			(end 1.700022 -2.4257)
			(stroke
				(width 0.1524)
				(type default)
			)
			(layer "F.SilkS")
		)
		(fp_line
			(start 1.700022 -1.3843)
			(end 1.700022 -1.1557)
			(stroke
				(width 0.1524)
				(type default)
			)
			(layer "F.SilkS")
		)
		(fp_line
			(start 1.700022 -0.1143)
			(end 1.700022 0.1143)
			(stroke
				(width 0.1524)
				(type default)
			)
			(layer "F.SilkS")
		)
		(fp_line
			(start 1.700022 1.1557)
			(end 1.700022 1.3843)
			(stroke
				(width 0.1524)
				(type default)
			)
			(layer "F.SilkS")
		)
		(fp_line
			(start 1.700022 2.4257)
			(end 1.700022 2.739898)
			(stroke
				(width 0.1524)
				(type default)
			)
			(layer "F.SilkS")
		)
		(fp_line
			(start 1.700022 2.739898)
			(end -1.700022 2.739898)
			(stroke
				(width 0.1524)
				(type default)
			)
			(layer "F.SilkS")
		)
		(fp_poly
			(pts
				(xy -3.383534 -1.905) (xy -4.399534 -1.397) (xy -4.399534 -2.413)
			)
			(stroke
				(width 0)
				(type default)
			)
			(fill yes)
			(layer "F.SilkS")
		)
		(fp_line
			(start -1.700022 -2.739898)
			(end 1.700022 -2.739898)
			(stroke
				(width 0.1)
				(type default)
			)
			(layer "F.Fab")
		)
		(fp_line
			(start -1.700022 2.739898)
			(end -1.700022 -2.739898)
			(stroke
				(width 0.1)
				(type default)
			)
			(layer "F.Fab")
		)
		(fp_line
			(start 1.700022 -2.739898)
			(end 1.700022 2.739898)
			(stroke
				(width 0.1)
				(type default)
			)
			(layer "F.Fab")
		)
		(fp_line
			(start 1.700022 2.739898)
			(end -1.700022 2.739898)
			(stroke
				(width 0.1)
				(type default)
			)
			(layer "F.Fab")
		)
		(fp_poly
			(pts
				(xy -4.399534 -2.413) (xy -4.399534 -1.397) (xy -3.383534 -1.905)
			)
			(stroke
				(width 0)
				(type default)
			)
			(fill yes)
			(layer "F.Fab")
		)
		(pad "1" smd rect
			(at -2.050034 -1.905 270)
			(size 0.762 2.413)
			(layers "F.Cu" "F.Mask" "F.Paste")
			(net "CPU0_BP0")
		)
		(pad "2" smd rect
			(at 2.050034 -1.905 270)
			(size 0.762 2.413)
			(layers "F.Cu" "F.Mask" "F.Paste")
			(net "GND")
		)
		(pad "3" smd rect
			(at -2.050034 -0.635 270)
			(size 0.762 2.413)
			(layers "F.Cu" "F.Mask" "F.Paste")
			(net "CPU0_BP1")
		)
		(pad "4" smd rect
			(at 2.050034 -0.635 270)
			(size 0.762 2.413)
			(layers "F.Cu" "F.Mask" "F.Paste")
			(net "GND")
		)
		(pad "5" smd rect
			(at -2.050034 0.635 270)
			(size 0.762 2.413)
			(layers "F.Cu" "F.Mask" "F.Paste")
			(net "CPU0_BP2")
		)
		(pad "6" smd rect
			(at 2.050034 0.635 270)
			(size 0.762 2.413)
			(layers "F.Cu" "F.Mask" "F.Paste")
			(net "GND")
		)
		(pad "7" smd rect
			(at -2.050034 1.905 270)
			(size 0.762 2.413)
			(layers "F.Cu" "F.Mask" "F.Paste")
			(net "CPU0_BP3")
		)
		(pad "8" smd rect
			(at 2.050034 1.905 270)
			(size 0.762 2.413)
			(layers "F.Cu" "F.Mask" "F.Paste")
			(net "GND")
		)
	)
	(footprint ""
		(layer "F.Cu")
		(at 448.61988 -94.602808 180)
		(property "Reference" "R4094"
			(at 0 0 180)
			(layer "F.SilkS")
			(hide yes)
			(effects
				(font
					(size 1.27 1.27)
				)
			)
		)
		(property "Value" ""
			(at 0 0 180)
			(layer "F.Fab")
			(effects
				(font
					(size 1.27 1.27)
				)
			)
		)
		(duplicate_pad_numbers_are_jumpers no)
		(fp_line
			(start 0.7874 0.4064)
			(end -0.7874 0.4064)
			(stroke
				(width 0.1524)
				(type default)
			)
			(layer "F.SilkS")
		)
		(fp_line
			(start 0.7874 -0.4064)
			(end 0.7874 0.4064)
			(stroke
				(width 0.1524)
				(type default)
			)
			(layer "F.SilkS")
		)
		(fp_line
			(start -0.7874 0.4064)
			(end -0.7874 -0.4064)
			(stroke
				(width 0.1524)
				(type default)
			)
			(layer "F.SilkS")
		)
		(fp_line
			(start -0.7874 -0.4064)
			(end 0.7874 -0.4064)
			(stroke
				(width 0.1524)
				(type default)
			)
			(layer "F.SilkS")
		)
		(fp_line
			(start 0.67945 0.3048)
			(end 0.120396 0.3048)
			(stroke
				(width 0.1)
				(type default)
			)
			(layer "F.Fab")
		)
		(fp_line
			(start 0.67945 -0.3048)
			(end 0.67945 0.3048)
			(stroke
				(width 0.1)
				(type default)
			)
			(layer "F.Fab")
		)
		(fp_line
			(start 0.12065 -0.2794)
			(end 0.12065 -0.3048)
			(stroke
				(width 0.1)
				(type default)
			)
			(layer "F.Fab")
		)
		(fp_line
			(start 0.12065 -0.3048)
			(end 0.67945 -0.3048)
			(stroke
				(width 0.1)
				(type default)
			)
			(layer "F.Fab")
		)
		(fp_line
			(start 0.120396 0.3048)
			(end 0.120396 0.2794)
			(stroke
				(width 0.1)
				(type default)
			)
			(layer "F.Fab")
		)
		(fp_line
			(start 0.120396 0.2794)
			(end -0.12065 0.2794)
			(stroke
				(width 0.1)
				(type default)
			)
			(layer "F.Fab")
		)
		(fp_line
			(start -0.12065 0.3048)
			(end -0.67945 0.3048)
			(stroke
				(width 0.1)
				(type default)
			)
			(layer "F.Fab")
		)
		(fp_line
			(start -0.12065 0.2794)
			(end -0.12065 0.3048)
			(stroke
				(width 0.1)
				(type default)
			)
			(layer "F.Fab")
		)
		(fp_line
			(start -0.12065 -0.2794)
			(end 0.12065 -0.2794)
			(stroke
				(width 0.1)
				(type default)
			)
			(layer "F.Fab")
		)
		(fp_line
			(start -0.12065 -0.305054)
			(end -0.12065 -0.2794)
			(stroke
				(width 0.1)
				(type default)
			)
			(layer "F.Fab")
		)
		(fp_line
			(start -0.67945 0.3048)
			(end -0.67945 -0.305054)
			(stroke
				(width 0.1)
				(type default)
			)
			(layer "F.Fab")
		)
		(fp_line
			(start -0.67945 -0.305054)
			(end -0.12065 -0.305054)
			(stroke
				(width 0.1)
				(type default)
			)
			(layer "F.Fab")
		)
		(pad "1" smd circle
			(at -0.40005 0 180)
			(size 0 0)
			(layers "F.Cu" "F.Mask" "F.Paste")
			(net "P3V3_AUX")
		)
		(pad "2" smd circle
			(at 0.40005 0 180)
			(size 0 0)
			(layers "F.Cu" "F.Mask" "F.Paste")
			(net "OCP_SFF_P3V3_ADC_ALERT_R")
		)
	)
	(footprint ""
		(layer "F.Cu")
		(at 105.659936 -127.768096 90)
		(property "Reference" "R1441"
			(at 0 0 90)
			(layer "F.SilkS")
			(hide yes)
			(effects
				(font
					(size 1.27 1.27)
				)
			)
		)
		(property "Value" ""
			(at 0 0 90)
			(layer "F.Fab")
			(effects
				(font
					(size 1.27 1.27)
				)
			)
		)
		(duplicate_pad_numbers_are_jumpers no)
		(fp_line
			(start 0.7874 -0.4064)
			(end 0.7874 0.4064)
			(stroke
				(width 0.1524)
				(type default)
			)
			(layer "F.SilkS")
		)
		(fp_line
			(start -0.7874 -0.4064)
			(end 0.7874 -0.4064)
			(stroke
				(width 0.1524)
				(type default)
			)
			(layer "F.SilkS")
		)
		(fp_line
			(start 0.7874 0.4064)
			(end -0.7874 0.4064)
			(stroke
				(width 0.1524)
				(type default)
			)
			(layer "F.SilkS")
		)
		(fp_line
			(start -0.7874 0.4064)
			(end -0.7874 -0.4064)
			(stroke
				(width 0.1524)
				(type default)
			)
			(layer "F.SilkS")
		)
		(fp_line
			(start -0.12065 -0.305054)
			(end -0.12065 -0.2794)
			(stroke
				(width 0.1)
				(type default)
			)
			(layer "F.Fab")
		)
		(fp_line
			(start -0.67945 -0.305054)
			(end -0.12065 -0.305054)
			(stroke
				(width 0.1)
				(type default)
			)
			(layer "F.Fab")
		)
		(fp_line
			(start 0.67945 -0.3048)
			(end 0.67945 0.3048)
			(stroke
				(width 0.1)
				(type default)
			)
			(layer "F.Fab")
		)
		(fp_line
			(start 0.12065 -0.3048)
			(end 0.67945 -0.3048)
			(stroke
				(width 0.1)
				(type default)
			)
			(layer "F.Fab")
		)
		(fp_line
			(start 0.12065 -0.2794)
			(end 0.12065 -0.3048)
			(stroke
				(width 0.1)
				(type default)
			)
			(layer "F.Fab")
		)
		(fp_line
			(start -0.12065 -0.2794)
			(end 0.12065 -0.2794)
			(stroke
				(width 0.1)
				(type default)
			)
			(layer "F.Fab")
		)
		(fp_line
			(start 0.120396 0.2794)
			(end -0.12065 0.2794)
			(stroke
				(width 0.1)
				(type default)
			)
			(layer "F.Fab")
		)
		(fp_line
			(start -0.12065 0.2794)
			(end -0.12065 0.3048)
			(stroke
				(width 0.1)
				(type default)
			)
			(layer "F.Fab")
		)
		(fp_line
			(start 0.67945 0.3048)
			(end 0.120396 0.3048)
			(stroke
				(width 0.1)
				(type default)
			)
			(layer "F.Fab")
		)
		(fp_line
			(start 0.120396 0.3048)
			(end 0.120396 0.2794)
			(stroke
				(width 0.1)
				(type default)
			)
			(layer "F.Fab")
		)
		(fp_line
			(start -0.12065 0.3048)
			(end -0.67945 0.3048)
			(stroke
				(width 0.1)
				(type default)
			)
			(layer "F.Fab")
		)
		(fp_line
			(start -0.67945 0.3048)
			(end -0.67945 -0.305054)
			(stroke
				(width 0.1)
				(type default)
			)
			(layer "F.Fab")
		)
		(pad "1" smd circle
			(at -0.40005 0 90)
			(size 0 0)
			(layers "F.Cu" "F.Mask" "F.Paste")
			(net "PWRGD_P12V_MEM_CPU1_EN")
		)
		(pad "2" smd circle
			(at 0.40005 0 90)
			(size 0 0)
			(layers "F.Cu" "F.Mask" "F.Paste")
			(net "GND")
		)
	)
	(footprint ""
		(layer "F.Cu")
		(at 22.479 -365.76)
		(property "Reference" "R8250"
			(at 0 0 0)
			(layer "F.SilkS")
			(hide yes)
			(effects
				(font
					(size 1.27 1.27)
				)
			)
		)
		(property "Value" ""
			(at 0 0 0)
			(layer "F.Fab")
			(effects
				(font
					(size 1.27 1.27)
				)
			)
		)
		(duplicate_pad_numbers_are_jumpers no)
		(fp_line
			(start -0.7874 -0.4064)
			(end 0.7874 -0.4064)
			(stroke
				(width 0.1524)
				(type default)
			)
			(layer "F.SilkS")
		)
		(fp_line
			(start -0.7874 0.4064)
			(end -0.7874 -0.4064)
			(stroke
				(width 0.1524)
				(type default)
			)
			(layer "F.SilkS")
		)
		(fp_line
			(start 0.7874 -0.4064)
			(end 0.7874 0.4064)
			(stroke
				(width 0.1524)
				(type default)
			)
			(layer "F.SilkS")
		)
		(fp_line
			(start 0.7874 0.4064)
			(end -0.7874 0.4064)
			(stroke
				(width 0.1524)
				(type default)
			)
			(layer "F.SilkS")
		)
		(fp_line
			(start -0.67945 -0.305054)
			(end -0.12065 -0.305054)
			(stroke
				(width 0.1)
				(type default)
			)
			(layer "F.Fab")
		)
		(fp_line
			(start -0.67945 0.3048)
			(end -0.67945 -0.305054)
			(stroke
				(width 0.1)
				(type default)
			)
			(layer "F.Fab")
		)
		(fp_line
			(start -0.12065 -0.305054)
			(end -0.12065 -0.2794)
			(stroke
				(width 0.1)
				(type default)
			)
			(layer "F.Fab")
		)
		(fp_line
			(start -0.12065 -0.2794)
			(end 0.12065 -0.2794)
			(stroke
				(width 0.1)
				(type default)
			)
			(layer "F.Fab")
		)
		(fp_line
			(start -0.12065 0.2794)
			(end -0.12065 0.3048)
			(stroke
				(width 0.1)
				(type default)
			)
			(layer "F.Fab")
		)
		(fp_line
			(start -0.12065 0.3048)
			(end -0.67945 0.3048)
			(stroke
				(width 0.1)
				(type default)
			)
			(layer "F.Fab")
		)
		(fp_line
			(start 0.120396 0.2794)
			(end -0.12065 0.2794)
			(stroke
				(width 0.1)
				(type default)
			)
			(layer "F.Fab")
		)
		(fp_line
			(start 0.120396 0.3048)
			(end 0.120396 0.2794)
			(stroke
				(width 0.1)
				(type default)
			)
			(layer "F.Fab")
		)
		(fp_line
			(start 0.12065 -0.3048)
			(end 0.67945 -0.3048)
			(stroke
				(width 0.1)
				(type default)
			)
			(layer "F.Fab")
		)
		(fp_line
			(start 0.12065 -0.2794)
			(end 0.12065 -0.3048)
			(stroke
				(width 0.1)
				(type default)
			)
			(layer "F.Fab")
		)
		(fp_line
			(start 0.67945 -0.3048)
			(end 0.67945 0.3048)
			(stroke
				(width 0.1)
				(type default)
			)
			(layer "F.Fab")
		)
		(fp_line
			(start 0.67945 0.3048)
			(end 0.120396 0.3048)
			(stroke
				(width 0.1)
				(type default)
			)
			(layer "F.Fab")
		)
		(pad "1" smd circle
			(at -0.40005 0)
			(size 0 0)
			(layers "F.Cu" "F.Mask" "F.Paste")
			(net "PVDDCR_CPU1_P1_SMB_ALERT")
		)
		(pad "2" smd circle
			(at 0.40005 0)
			(size 0 0)
			(layers "F.Cu" "F.Mask" "F.Paste")
			(net "PVDDCR_CPU1_P1_SMB_ALERT_R")
		)
	)
	(footprint ""
		(layer "F.Cu")
		(at 396.58163 -146.354292 -90)
		(property "Reference" "C1227"
			(at 0 0 270)
			(layer "F.SilkS")
			(hide yes)
			(effects
				(font
					(size 1.27 1.27)
				)
			)
		)
		(property "Value" ""
			(at 0 0 270)
			(layer "F.Fab")
			(effects
				(font
					(size 1.27 1.27)
				)
			)
		)
		(duplicate_pad_numbers_are_jumpers no)
		(fp_line
			(start -0.7874 0.4064)
			(end -0.7874 -0.4064)
			(stroke
				(width 0.1524)
				(type default)
			)
			(layer "F.SilkS")
		)
		(fp_line
			(start 0.7874 0.4064)
			(end -0.7874 0.4064)
			(stroke
				(width 0.1524)
				(type default)
			)
			(layer "F.SilkS")
		)
		(fp_line
			(start -0.7874 -0.4064)
			(end 0.7874 -0.4064)
			(stroke
				(width 0.1524)
				(type default)
			)
			(layer "F.SilkS")
		)
		(fp_line
			(start 0.7874 -0.4064)
			(end 0.7874 0.4064)
			(stroke
				(width 0.1524)
				(type default)
			)
			(layer "F.SilkS")
		)
		(fp_line
			(start -0.67945 0.3048)
			(end -0.67945 -0.305054)
			(stroke
				(width 0.1)
				(type default)
			)
			(layer "F.Fab")
		)
		(fp_line
			(start -0.12065 0.3048)
			(end -0.67945 0.3048)
			(stroke
				(width 0.1)
				(type default)
			)
			(layer "F.Fab")
		)
		(fp_line
			(start 0.120396 0.3048)
			(end 0.120396 0.2794)
			(stroke
				(width 0.1)
				(type default)
			)
			(layer "F.Fab")
		)
		(fp_line
			(start 0.67945 0.3048)
			(end 0.120396 0.3048)
			(stroke
				(width 0.1)
				(type default)
			)
			(layer "F.Fab")
		)
		(fp_line
			(start -0.12065 0.2794)
			(end -0.12065 0.3048)
			(stroke
				(width 0.1)
				(type default)
			)
			(layer "F.Fab")
		)
		(fp_line
			(start 0.120396 0.2794)
			(end -0.12065 0.2794)
			(stroke
				(width 0.1)
				(type default)
			)
			(layer "F.Fab")
		)
		(fp_line
			(start -0.12065 -0.2794)
			(end 0.12065 -0.2794)
			(stroke
				(width 0.1)
				(type default)
			)
			(layer "F.Fab")
		)
		(fp_line
			(start 0.12065 -0.2794)
			(end 0.12065 -0.3048)
			(stroke
				(width 0.1)
				(type default)
			)
			(layer "F.Fab")
		)
		(fp_line
			(start 0.12065 -0.3048)
			(end 0.67945 -0.3048)
			(stroke
				(width 0.1)
				(type default)
			)
			(layer "F.Fab")
		)
		(fp_line
			(start 0.67945 -0.3048)
			(end 0.67945 0.3048)
			(stroke
				(width 0.1)
				(type default)
			)
			(layer "F.Fab")
		)
		(fp_line
			(start -0.67945 -0.305054)
			(end -0.12065 -0.305054)
			(stroke
				(width 0.1)
				(type default)
			)
			(layer "F.Fab")
		)
		(fp_line
			(start -0.12065 -0.305054)
			(end -0.12065 -0.2794)
			(stroke
				(width 0.1)
				(type default)
			)
			(layer "F.Fab")
		)
		(pad "1" smd circle
			(at -0.40005 0 270)
			(size 0 0)
			(layers "F.Cu" "F.Mask" "F.Paste")
			(net "P5V")
		)
		(pad "2" smd circle
			(at 0.40005 0 270)
			(size 0 0)
			(layers "F.Cu" "F.Mask" "F.Paste")
			(net "GND")
		)
	)
	(footprint ""
		(layer "F.Cu")
		(at 450.008752 -395.699234 90)
		(property "Reference" "PR6563"
			(at 0 0 90)
			(layer "F.SilkS")
			(hide yes)
			(effects
				(font
					(size 1.27 1.27)
				)
			)
		)
		(property "Value" ""
			(at 0 0 90)
			(layer "F.Fab")
			(effects
				(font
					(size 1.27 1.27)
				)
			)
		)
		(duplicate_pad_numbers_are_jumpers no)
		(fp_line
			(start 0.7874 -0.4064)
			(end 0.7874 0.4064)
			(stroke
				(width 0.1524)
				(type default)
			)
			(layer "F.SilkS")
		)
		(fp_line
			(start -0.7874 -0.4064)
			(end 0.7874 -0.4064)
			(stroke
				(width 0.1524)
				(type default)
			)
			(layer "F.SilkS")
		)
		(fp_line
			(start 0.7874 0.4064)
			(end -0.7874 0.4064)
			(stroke
				(width 0.1524)
				(type default)
			)
			(layer "F.SilkS")
		)
		(fp_line
			(start -0.7874 0.4064)
			(end -0.7874 -0.4064)
			(stroke
				(width 0.1524)
				(type default)
			)
			(layer "F.SilkS")
		)
		(fp_line
			(start -0.12065 -0.305054)
			(end -0.12065 -0.2794)
			(stroke
				(width 0.1)
				(type default)
			)
			(layer "F.Fab")
		)
		(fp_line
			(start -0.67945 -0.305054)
			(end -0.12065 -0.305054)
			(stroke
				(width 0.1)
				(type default)
			)
			(layer "F.Fab")
		)
		(fp_line
			(start 0.67945 -0.3048)
			(end 0.67945 0.3048)
			(stroke
				(width 0.1)
				(type default)
			)
			(layer "F.Fab")
		)
		(fp_line
			(start 0.12065 -0.3048)
			(end 0.67945 -0.3048)
			(stroke
				(width 0.1)
				(type default)
			)
			(layer "F.Fab")
		)
		(fp_line
			(start 0.12065 -0.2794)
			(end 0.12065 -0.3048)
			(stroke
				(width 0.1)
				(type default)
			)
			(layer "F.Fab")
		)
		(fp_line
			(start -0.12065 -0.2794)
			(end 0.12065 -0.2794)
			(stroke
				(width 0.1)
				(type default)
			)
			(layer "F.Fab")
		)
		(fp_line
			(start 0.120396 0.2794)
			(end -0.12065 0.2794)
			(stroke
				(width 0.1)
				(type default)
			)
			(layer "F.Fab")
		)
		(fp_line
			(start -0.12065 0.2794)
			(end -0.12065 0.3048)
			(stroke
				(width 0.1)
				(type default)
			)
			(layer "F.Fab")
		)
		(fp_line
			(start 0.67945 0.3048)
			(end 0.120396 0.3048)
			(stroke
				(width 0.1)
				(type default)
			)
			(layer "F.Fab")
		)
		(fp_line
			(start 0.120396 0.3048)
			(end 0.120396 0.2794)
			(stroke
				(width 0.1)
				(type default)
			)
			(layer "F.Fab")
		)
		(fp_line
			(start -0.12065 0.3048)
			(end -0.67945 0.3048)
			(stroke
				(width 0.1)
				(type default)
			)
			(layer "F.Fab")
		)
		(fp_line
			(start -0.67945 0.3048)
			(end -0.67945 -0.305054)
			(stroke
				(width 0.1)
				(type default)
			)
			(layer "F.Fab")
		)
		(pad "1" smd circle
			(at -0.40005 0 90)
			(size 0 0)
			(layers "F.Cu" "F.Mask" "F.Paste")
			(net "SW_P0V9_RETIMER_CPU0_SW2_RC")
		)
		(pad "2" smd circle
			(at 0.40005 0 90)
			(size 0 0)
			(layers "F.Cu" "F.Mask" "F.Paste")
			(net "GND")
		)
	)
)
